# S9S_MB_2U (Grand Teton) — schematic netlist excerpt (pin names and nets, part order shuffled) for the footprints in the layout excerpt that follows; sources: Cadence DE-HDL packaged netlist, KiCad conversion of 03242023_DA0F0TMBIJ0_F0T_Motherboard_J_brd_V01_OCP.brd

R2452  Q_RES  0 5% CHIP  pkg 0402LF  page 214 : A = FM_ESPI_PLD_R_EN ; B = FM_ESPI_PLD_R1_EN
R3103  Q_RES  0 5% CHIP  pkg 0402LF  page 228 : A = IRQ_SML0_ALERT_R_N ; B = IRQ_SML0_ALERT_R1_N

(kicad_pcb
	(version 20260206)
	(generator "pcbnew")
	(generator_version "10.0")
	(general
		(thickness 1.6)
		(legacy_teardrops no)
	)
	(paper "A4")
	(title_block
		(title "03242023_DA0F0TMBIJ0_F0T_Motherboard_J_brd_V01_OCP.brd")
		(comment 1 "Grand Teton / footprints 1486-1487 of 6105")
	)
	(layers
		(0 "F.Cu" signal "TOP")
		(4 "In1.Cu" signal "GND")
		(6 "In2.Cu" signal "IN1")
		(8 "In3.Cu" signal "GND1")
		(10 "In4.Cu" signal "IN2")
		(12 "In5.Cu" signal "GND2")
		(14 "In6.Cu" signal "IN3")
		(16 "In7.Cu" signal "GND3")
		(18 "In8.Cu" signal "VCC")
		(20 "In9.Cu" signal "VCC1")
		(22 "In10.Cu" signal "GND4")
		(24 "In11.Cu" signal "IN4")
		(26 "In12.Cu" signal "GND5")
		(28 "In13.Cu" signal "IN5")
		(30 "In14.Cu" signal "GND6")
		(32 "In15.Cu" signal "IN6")
		(34 "In16.Cu" signal "GND7")
		(2 "B.Cu" signal "BOTTOM")
		(9 "F.Adhes" user "F.Adhesive")
		(11 "B.Adhes" user "B.Adhesive")
		(13 "F.Paste" user "Package Geometry/Pastemask Top")
		(15 "B.Paste" user "Package Geometry/Pastemask Bottom")
		(5 "F.SilkS" user "Ref Des/Silkscreen Top")
		(7 "B.SilkS" user "Ref Des/Silkscreen Bottom")
		(1 "F.Mask" user "Board Geometry/Soldermask Top")
		(3 "B.Mask" user "Board Geometry/Soldermask Bottom")
		(17 "Dwgs.User" user "User.Drawings")
		(19 "Cmts.User" user "User.Comments")
		(21 "Eco1.User" user "User.Eco1")
		(23 "Eco2.User" user "User.Eco2")
		(25 "Edge.Cuts" user "Board Geometry/Outline")
		(27 "Margin" user)
		(31 "F.CrtYd" user "Package Geometry/Place Bound Top")
		(29 "B.CrtYd" user "Package Geometry/Place Bound Bottom")
		(35 "F.Fab" user "Ref Des/Assembly Top")
		(33 "B.Fab" user "Ref Des/Assembly Bottom")
	)
	(footprint ""
		(layer "F.Cu")
		(at 331.224636 -16.401288)
		(property "Reference" "R2452"
			(at 0 0 0)
			(layer "F.SilkS")
			(hide yes)
			(effects
				(font
					(size 1.27 1.27)
				)
			)
		)
		(property "Value" ""
			(at 0 0 0)
			(layer "F.Fab")
			(effects
				(font
					(size 1.27 1.27)
				)
			)
		)
		(duplicate_pad_numbers_are_jumpers no)
		(fp_line
			(start -0.7874 -0.4064)
			(end 0.7874 -0.4064)
			(stroke
				(width 0.1524)
				(type default)
			)
			(layer "F.SilkS")
		)
		(fp_line
			(start -0.7874 0.4064)
			(end -0.7874 -0.4064)
			(stroke
				(width 0.1524)
				(type default)
			)
			(layer "F.SilkS")
		)
		(fp_line
			(start 0.7874 -0.4064)
			(end 0.7874 0.4064)
			(stroke
				(width 0.1524)
				(type default)
			)
			(layer "F.SilkS")
		)
		(fp_line
			(start 0.7874 0.4064)
			(end -0.7874 0.4064)
			(stroke
				(width 0.1524)
				(type default)
			)
			(layer "F.SilkS")
		)
		(fp_line
			(start -0.67945 -0.305054)
			(end -0.12065 -0.305054)
			(stroke
				(width 0.1)
				(type default)
			)
			(layer "F.Fab")
		)
		(fp_line
			(start -0.67945 0.3048)
			(end -0.67945 -0.305054)
			(stroke
				(width 0.1)
				(type default)
			)
			(layer "F.Fab")
		)
		(fp_line
			(start -0.12065 -0.305054)
			(end -0.12065 -0.2794)
			(stroke
				(width 0.1)
				(type default)
			)
			(layer "F.Fab")
		)
		(fp_line
			(start -0.12065 -0.2794)
			(end 0.12065 -0.2794)
			(stroke
				(width 0.1)
				(type default)
			)
			(layer "F.Fab")
		)
		(fp_line
			(start -0.12065 0.2794)
			(end -0.12065 0.3048)
			(stroke
				(width 0.1)
				(type default)
			)
			(layer "F.Fab")
		)
		(fp_line
			(start -0.12065 0.3048)
			(end -0.67945 0.3048)
			(stroke
				(width 0.1)
				(type default)
			)
			(layer "F.Fab")
		)
		(fp_line
			(start 0.120396 0.2794)
			(end -0.12065 0.2794)
			(stroke
				(width 0.1)
				(type default)
			)
			(layer "F.Fab")
		)
		(fp_line
			(start 0.120396 0.3048)
			(end 0.120396 0.2794)
			(stroke
				(width 0.1)
				(type default)
			)
			(layer "F.Fab")
		)
		(fp_line
			(start 0.12065 -0.3048)
			(end 0.67945 -0.3048)
			(stroke
				(width 0.1)
				(type default)
			)
			(layer "F.Fab")
		)
		(fp_line
			(start 0.12065 -0.2794)
			(end 0.12065 -0.3048)
			(stroke
				(width 0.1)
				(type default)
			)
			(layer "F.Fab")
		)
		(fp_line
			(start 0.67945 -0.3048)
			(end 0.67945 0.3048)
			(stroke
				(width 0.1)
				(type default)
			)
			(layer "F.Fab")
		)
		(fp_line
			(start 0.67945 0.3048)
			(end 0.120396 0.3048)
			(stroke
				(width 0.1)
				(type default)
			)
			(layer "F.Fab")
		)
		(pad "1" smd circle
			(at -0.40005 0)
			(size 0 0)
			(layers "F.Cu" "F.Mask" "F.Paste")
			(net "FM_ESPI_PLD_R_EN")
		)
		(pad "2" smd circle
			(at 0.40005 0)
			(size 0 0)
			(layers "F.Cu" "F.Mask" "F.Paste")
			(net "FM_ESPI_PLD_R1_EN")
		)
	)
	(footprint ""
		(layer "F.Cu")
		(at 27.79395 -58.960512 180)
		(property "Reference" "R3103"
			(at 0 0 180)
			(layer "F.SilkS")
			(hide yes)
			(effects
				(font
					(size 1.27 1.27)
				)
			)
		)
		(property "Value" ""
			(at 0 0 180)
			(layer "F.Fab")
			(effects
				(font
					(size 1.27 1.27)
				)
			)
		)
		(duplicate_pad_numbers_are_jumpers no)
		(fp_line
			(start 0.7874 0.4064)
			(end -0.7874 0.4064)
			(stroke
				(width 0.1524)
				(type default)
			)
			(layer "F.SilkS")
		)
		(fp_line
			(start 0.7874 -0.4064)
			(end 0.7874 0.4064)
			(stroke
				(width 0.1524)
				(type default)
			)
			(layer "F.SilkS")
		)
		(fp_line
			(start -0.7874 0.4064)
			(end -0.7874 -0.4064)
			(stroke
				(width 0.1524)
				(type default)
			)
			(layer "F.SilkS")
		)
		(fp_line
			(start -0.7874 -0.4064)
			(end 0.7874 -0.4064)
			(stroke
				(width 0.1524)
				(type default)
			)
			(layer "F.SilkS")
		)
		(fp_line
			(start 0.67945 0.3048)
			(end 0.120396 0.3048)
			(stroke
				(width 0.1)
				(type default)
			)
			(layer "F.Fab")
		)
		(fp_line
			(start 0.67945 -0.3048)
			(end 0.67945 0.3048)
			(stroke
				(width 0.1)
				(type default)
			)
			(layer "F.Fab")
		)
		(fp_line
			(start 0.12065 -0.2794)
			(end 0.12065 -0.3048)
			(stroke
				(width 0.1)
				(type default)
			)
			(layer "F.Fab")
		)
		(fp_line
			(start 0.12065 -0.3048)
			(end 0.67945 -0.3048)
			(stroke
				(width 0.1)
				(type default)
			)
			(layer "F.Fab")
		)
		(fp_line
			(start 0.120396 0.3048)
			(end 0.120396 0.2794)
			(stroke
				(width 0.1)
				(type default)
			)
			(layer "F.Fab")
		)
		(fp_line
			(start 0.120396 0.2794)
			(end -0.12065 0.2794)
			(stroke
				(width 0.1)
				(type default)
			)
			(layer "F.Fab")
		)
		(fp_line
			(start -0.12065 0.3048)
			(end -0.67945 0.3048)
			(stroke
				(width 0.1)
				(type default)
			)
			(layer "F.Fab")
		)
		(fp_line
			(start -0.12065 0.2794)
			(end -0.12065 0.3048)
			(stroke
				(width 0.1)
				(type default)
			)
			(layer "F.Fab")
		)
		(fp_line
			(start -0.12065 -0.2794)
			(end 0.12065 -0.2794)
			(stroke
				(width 0.1)
				(type default)
			)
			(layer "F.Fab")
		)
		(fp_line
			(start -0.12065 -0.305054)
			(end -0.12065 -0.2794)
			(stroke
				(width 0.1)
				(type default)
			)
			(layer "F.Fab")
		)
		(fp_line
			(start -0.67945 0.3048)
			(end -0.67945 -0.305054)
			(stroke
				(width 0.1)
				(type default)
			)
			(layer "F.Fab")
		)
		(fp_line
			(start -0.67945 -0.305054)
			(end -0.12065 -0.305054)
			(stroke
				(width 0.1)
				(type default)
			)
			(layer "F.Fab")
		)
		(pad "1" smd circle
			(at -0.40005 0 180)
			(size 0 0)
			(layers "F.Cu" "F.Mask" "F.Paste")
			(net "IRQ_SML0_ALERT_R_N")
		)
		(pad "2" smd circle
			(at 0.40005 0 180)
			(size 0 0)
			(layers "F.Cu" "F.Mask" "F.Paste")
			(net "IRQ_SML0_ALERT_R1_N")
		)
	)
)
